# ZAIUS-LBB-EVT2-X01-BOM-X03-20161116.xls — Single-Sole Source Parts List (bom)
| FOXCONN TECHNOLOGY GROUP |  |  |  |  |  |  |  |  |  |  |  |  |  |  |  |  |  |
| BILL OF MATERIAL |  |  |  |  |  |  |  |  |  |  |  |  |  |  |  |  |  |
| REV OF  BOM |  | CUSTOMER | DELL |  | CUSTOMER P/N |  | PWA P/N： | PWA DESCRIPTION |  |  | PRODUCT CODE |  |  | PWA REV |  | DATE |  |
| Sourcing (Single or Sole | Critical Commodity (Y or N) | Component Class (1, 2, Other) | Dell PSL (Y/N) | Item Number | Foxconn P/N | Dell P/N | Part Description | Mfr. 1 | Mfr Part # 1 | Proposed Mfr. 2 | Proposed Mfr. 2 PN | Qty | RoHS Status | Location | 2nd Source Qual Build: | Dell Comments | ODM Comments |
